# BASEBOARD_FAB2 (Tioga Pass) — schematic netlist excerpt (pin names and nets, part order shuffled) for the footprints in the layout excerpt that follows; sources: Cadence DE-HDL packaged netlist, KiCad conversion of Wiwynn_Tioga_Pass_MB.brd

J1G2  SCONN288_H44441004  SCONN  pkg PIP  page 79
  \12v\(1)  = P12V_NVDIMM_GHJ
  VSS(93)  = GND
  DQ(4)  = M_H_DQ<5>
  VSS(92)  = GND
  DQ(0)  = M_H_DQ<1>
  VSS(91)  = GND
  DQS9P  = M_H_DQS_DP<9>
  DQS9N  = M_H_DQS_DN<9>
  VSS(90)  = GND
  DQ(6)  = M_H_DQ<7>
  VSS(89)  = GND
  DQ(2)  = M_H_DQ<3>
  VSS(88)  = GND
  DQ(12)  = M_H_DQ<13>
  VSS(87)  = GND
  DQ(8)  = M_H_DQ<9>
  VSS(86)  = GND
  DQS10P  = M_H_DQS_DP<10>
  DQS10N  = M_H_DQS_DN<10>
  VSS(85)  = GND
  DQ(14)  = M_H_DQ<15>
  VSS(84)  = GND
  DQ(10)  = M_H_DQ<11>
  VSS(83)  = GND
  DQ(20)  = M_H_DQ<21>
  VSS(82)  = GND
  DQ(16)  = M_H_DQ<17>
  VSS(81)  = GND
  DQS11P  = M_H_DQS_DP<11>
  DQS11N  = M_H_DQS_DN<11>
  VSS(80)  = GND
  DQ(22)  = M_H_DQ<23>
  VSS(79)  = GND
  DQ(18)  = M_H_DQ<19>
  VSS(78)  = GND
  DQ(28)  = M_H_DQ<29>
  VSS(77)  = GND
  DQ(24)  = M_H_DQ<25>
  VSS(76)  = GND
  DQS12P  = M_H_DQS_DP<12>
  DQS12N  = M_H_DQS_DN<12>
  VSS(75)  = GND
  DQ(30)  = M_H_DQ<31>
  VSS(74)  = GND
  DQ(26)  = M_H_DQ<27>
  VSS(73)  = GND
  CB(4)  = M_H_ECC<5>
  VSS(72)  = GND
  CB(0)  = M_H_ECC<1>
  VSS(71)  = GND
  DQS17P  = M_H_DQS_DP<17>
  DQS17N  = M_H_DQS_DN<17>
  VSS(70)  = GND
  CB(6)  = M_H_ECC<7>
  VSS(69)  = GND
  CB(2)  = M_H_ECC<3>
  VSS(68)  = GND
  RESET_N  = M_GHJ_RST_N
  VDD(25)  = PVDDQ_GHJ
  CKE(0)  = M_H_CKE<0>
  VDD(24)  = PVDDQ_GHJ
  ACT_N  = M_H_ACT_N
  BG(0)  = M_H_BG<0>
  VDD(23)  = PVDDQ_GHJ
  A12  = M_H_MA<12>
  A9  = M_H_MA<9>
  VDD(22)  = PVDDQ_GHJ
  A8  = M_H_MA<8>
  A6  = M_H_MA<6>
  VDD(21)  = PVDDQ_GHJ
  A3  = M_H_MA<3>
  A1  = M_H_MA<1>
  VDD(20)  = PVDDQ_GHJ
  CK0P  = M_H_CLK_DP<0>
  CK0N  = M_H_CLK_DN<0>
  VDD(19)  = PVDDQ_GHJ
  VTT(1)  = PVTT_GHJ
  EVENT_N  = FM_DIMM_EVENT_COD_N
  A0  = M_H_MA<0>
  VDD(18)  = PVDDQ_GHJ
  BA(0)  = M_H_BA<0>
  A16_RAS_N  = M_H_MA<16>
  VDD(17)  = PVDDQ_GHJ
  S0_N  = M_H_CS_N<0>
  VDD(16)  = PVDDQ_GHJ
  A15_CAS_N  = M_H_MA<15>
  ODT(0)  = M_H_ODT<0>
  VDD(15)  = PVDDQ_GHJ
  S1_N  = M_H_CS_N<1>
  VDD(14)  = PVDDQ_GHJ
  ODT(1)  = M_H_ODT<1>
  VDD(13)  = PVDDQ_GHJ
  S2_N_C(0)  = M_H_CS_N<2>
  VSS(67)  = GND
  DQ(36)  = M_H_DQ<37>
  VSS(66)  = GND
  DQ(32)  = M_H_DQ<33>
  VSS(65)  = GND
  DQS13P  = M_H_DQS_DP<13>
  DQS13N  = M_H_DQS_DN<13>
  VSS(64)  = GND
  DQ(38)  = M_H_DQ<39>
  VSS(63)  = GND
  DQ(34)  = M_H_DQ<35>
  VSS(62)  = GND
  DQ(44)  = M_H_DQ<45>
  VSS(61)  = GND
  DQ(40)  = M_H_DQ<41>
  VSS(60)  = GND
  DQS14P  = M_H_DQS_DP<14>
  DQS14N  = M_H_DQS_DN<14>
  VSS(59)  = GND
  DQ(46)  = M_H_DQ<47>
  VSS(58)  = GND
  DQ(42)  = M_H_DQ<43>
  VSS(57)  = GND
  DQ(52)  = M_H_DQ<53>
  VSS(56)  = GND
  DQ(48)  = M_H_DQ<49>
  VSS(55)  = GND
  DQS15P  = M_H_DQS_DP<15>
  DQS15N  = M_H_DQS_DN<15>
  VSS(54)  = GND
  DQ(54)  = M_H_DQ<55>
  VSS(53)  = GND
  DQ(50)  = M_H_DQ<51>
  VSS(52)  = GND
  DQ(60)  = M_H_DQ<61>
  VSS(51)  = GND
  DQ(56)  = M_H_DQ<57>
  VSS(50)  = GND
  DQS16P  = M_H_DQS_DP<16>
  DQS16N  = M_H_DQS_DN<16>
  VSS(49)  = GND
  DQ(62)  = M_H_DQ<63>
  VSS(48)  = GND
  DQ(58)  = M_H_DQ<59>
  VSS(47)  = GND
  SA(0)  = GND
  SA(1)  = PVPP_GHJ
  SCL  = SMB_DDR_GHJ_VPP_SCL
  VPP(4)  = PVPP_GHJ
  VPP(3)  = PVPP_GHJ
  RFU(2)  = TP_CH_H_DIMM_H0_RFU_2
  \12v\(0)  = P12V_NVDIMM_GHJ
  VREFCA  = M_H_VREF
  VSS(46)  = GND
  DQ(5)  = M_H_DQ<4>
  VSS(45)  = GND
  DQ(1)  = M_H_DQ<0>
  VSS(44)  = GND
  DQS0N  = M_H_DQS_DN<0>
  DQS0P  = M_H_DQS_DP<0>
  VSS(43)  = GND
  DQ(7)  = M_H_DQ<6>
  VSS(42)  = GND
  DQ(3)  = M_H_DQ<2>
  VSS(41)  = GND
  DQ(13)  = M_H_DQ<12>
  VSS(40)  = GND
  DQ(9)  = M_H_DQ<8>
  VSS(39)  = GND
  DQS1N  = M_H_DQS_DN<1>
  DQS1P  = M_H_DQS_DP<1>
  VSS(38)  = GND
  DQ(15)  = M_H_DQ<14>
  VSS(37)  = GND
  DQ(11)  = M_H_DQ<10>
  VSS(36)  = GND
  DQ(21)  = M_H_DQ<20>
  VSS(35)  = GND
  DQ(17)  = M_H_DQ<16>
  VSS(34)  = GND
  DQS2N  = M_H_DQS_DN<2>
  DQS2P  = M_H_DQS_DP<2>
  VSS(33)  = GND
  DQ(23)  = M_H_DQ<22>
  VSS(32)  = GND
  DQ(19)  = M_H_DQ<18>
  VSS(31)  = GND
  DQ(29)  = M_H_DQ<28>
  VSS(30)  = GND
  DQ(25)  = M_H_DQ<24>
  VSS(29)  = GND
  DQS3N  = M_H_DQS_DN<3>
  DQS3P  = M_H_DQS_DP<3>
  VSS(28)  = GND
  DQ(31)  = M_H_DQ<30>
  VSS(27)  = GND
  DQ(27)  = M_H_DQ<26>
  VSS(26)  = GND
  CB(5)  = M_H_ECC<4>
  VSS(25)  = GND
  CB(1)  = M_H_ECC<0>
  VSS(24)  = GND
  DQS8N  = M_H_DQS_DN<8>
  DQS8P  = M_H_DQS_DP<8>
  VSS(23)  = GND
  CB(7)  = M_H_ECC<6>
  VSS(22)  = GND
  CB(3)  = M_H_ECC<2>
  VSS(21)  = GND
  CKE(1)  = M_H_CKE<1>
  VDD(12)  = PVDDQ_GHJ
  RFU(0)  = TP_CH_H_DIMM_H0_RFU_0
  VDD(11)  = PVDDQ_GHJ
  BG(1)  = M_H_BG<1>
  ALERT_N  = M_H_ALERT_N
  VDD(10)  = PVDDQ_GHJ
  A11  = M_H_MA<11>
  A7  = M_H_MA<7>
  VDD(9)  = PVDDQ_GHJ
  A5  = M_H_MA<5>
  A4  = M_H_MA<4>
  VDD(8)  = PVDDQ_GHJ
  A2  = M_H_MA<2>
  VDD(7)  = PVDDQ_GHJ
  CK1P  = M_H_CLK_DP<1>
  CK1N  = M_H_CLK_DN<1>
  VDD(6)  = PVDDQ_GHJ
  VTT(0)  = PVTT_GHJ
  PAR  = M_H_PAR
  VDD(5)  = PVDDQ_GHJ
  BA(1)  = M_H_BA<1>
  A10  = M_H_MA<10>
  VDD(4)  = PVDDQ_GHJ
  RFU(1)  = TP_CH_H_DIMM_H0_RFU_1
  A14_WE_N  = M_H_MA<14>
  VDD(3)  = PVDDQ_GHJ
  SAVE_N_NC  = FM_ADR_COMPLETE_GHJ_N
  VDD(2)  = PVDDQ_GHJ
  A13  = M_H_MA<13>
  VDD(1)  = PVDDQ_GHJ
  A17  = M_H_MA<17>
  C(2)  = M_H_C<2>
  VDD(0)  = PVDDQ_GHJ
  S3_N_C(1)  = M_H_CS_N<3>
  SA(2)  = GND
  VSS(20)  = GND
  DQ(37)  = M_H_DQ<36>
  VSS(19)  = GND
  DQ(33)  = M_H_DQ<32>
  VSS(18)  = GND
  DQS4N  = M_H_DQS_DN<4>
  DQS4P  = M_H_DQS_DP<4>
  VSS(17)  = GND
  DQ(39)  = M_H_DQ<38>
  VSS(16)  = GND
  DQ(35)  = M_H_DQ<34>
  VSS(15)  = GND
  DQ(45)  = M_H_DQ<44>
  VSS(14)  = GND
  DQ(41)  = M_H_DQ<40>
  VSS(13)  = GND
  DQS5N  = M_H_DQS_DN<5>
  DQS5P  = M_H_DQS_DP<5>
  VSS(12)  = GND
  DQ(47)  = M_H_DQ<46>
  VSS(11)  = GND
  DQ(43)  = M_H_DQ<42>
  VSS(10)  = GND
  DQ(53)  = M_H_DQ<52>
  VSS(9)  = GND
  DQ(49)  = M_H_DQ<48>
  VSS(8)  = GND
  DQS6N  = M_H_DQS_DN<6>
  DQS6P  = M_H_DQS_DP<6>
  VSS(7)  = GND
  DQ(55)  = M_H_DQ<54>
  VSS(6)  = GND
  DQ(51)  = M_H_DQ<50>
  VSS(5)  = GND
  DQ(61)  = M_H_DQ<60>
  VSS(4)  = GND
  DQ(57)  = M_H_DQ<56>
  VSS(3)  = GND
  DQS7N  = M_H_DQS_DN<7>
  DQS7P  = M_H_DQS_DP<7>
  VSS(2)  = GND
  DQ(63)  = M_H_DQ<62>
  VSS(1)  = GND
  DQ(59)  = M_H_DQ<58>
  VSS(0)  = GND
  VDDSPD  = PVPP_GHJ
  SDA  = SMB_DDR_GHJ_VPP_SDA
  VPP(1)  = PVPP_GHJ
  VPP(0)  = PVPP_GHJ
  VPP(2)  = PVPP_GHJ

(kicad_pcb
	(version 20260206)
	(generator "pcbnew")
	(generator_version "10.0")
	(general
		(thickness 1.6)
		(legacy_teardrops no)
	)
	(paper "A4")
	(title_block
		(title "Wiwynn_Tioga_Pass_MB.brd")
		(comment 1 "Tioga Pass / footprint 2141 of 4770 (J1G2), pads 1-50 of 291")
	)
	(layers
		(0 "F.Cu" signal "TOP")
		(4 "In1.Cu" signal "L2GND")
		(6 "In2.Cu" signal "L3")
		(8 "In3.Cu" signal "L4GND")
		(10 "In4.Cu" signal "L5")
		(12 "In5.Cu" signal "L6GND")
		(14 "In6.Cu" signal "L7VCC")
		(16 "In7.Cu" signal "L8VCC")
		(18 "In8.Cu" signal "L9GND")
		(20 "In9.Cu" signal "L10")
		(22 "In10.Cu" signal "L11GND")
		(24 "In11.Cu" signal "L12")
		(26 "In12.Cu" signal "L13GND")
		(2 "B.Cu" signal "BOTTOM")
		(9 "F.Adhes" user "F.Adhesive")
		(11 "B.Adhes" user "B.Adhesive")
		(13 "F.Paste" user "Package Geometry/Pastemask Top")
		(15 "B.Paste" user "Package Geometry/Pastemask Bottom")
		(5 "F.SilkS" user "Ref Des/Silkscreen Top")
		(7 "B.SilkS" user "Ref Des/Silkscreen Bottom")
		(1 "F.Mask" user "Board Geometry/Soldermask Top")
		(3 "B.Mask" user "Board Geometry/Soldermask Bottom")
		(17 "Dwgs.User" user "User.Drawings")
		(19 "Cmts.User" user "User.Comments")
		(21 "Eco1.User" user "User.Eco1")
		(23 "Eco2.User" user "User.Eco2")
		(25 "Edge.Cuts" user "Board Geometry/Outline")
		(27 "Margin" user)
		(31 "F.CrtYd" user "Package Geometry/Place Bound Top")
		(29 "B.CrtYd" user "Package Geometry/Place Bound Bottom")
		(35 "F.Fab" user "Ref Des/Assembly Top")
		(33 "B.Fab" user "Ref Des/Assembly Bottom")
	)
	(footprint ""
		(layer "F.Cu")
		(at 29.699458 -5.822442 90)
		(property "Reference" "J1G2"
			(at 7.104888 34.562542 0)
			(unlocked yes)
			(layer "F.SilkS")
			(effects
				(font
					(size 0.7874 0.5842)
					(thickness 0.1524)
				)
				(justify left)
			)
		)
		(property "Value" ""
			(at 0 0 90)
			(layer "F.Fab")
			(effects
				(font
					(size 1.27 1.27)
				)
			)
		)
		(duplicate_pad_numbers_are_jumpers no)
		(pad "" thru_hole circle
			(at 2.29997 -5.649976 90)
			(size 2.8194 2.8194)
			(drill 2.4384)
			(layers "*.Cu" "*.Mask")
			(remove_unused_layers no)
			(clearance 0.127)
			(thermal_gap 0.127)
		)
		(pad "" thru_hole oval
			(at 2.29997 68.90004 90)
			(size 2.8194 1.5748)
			(drill oval 2.4384 1.1938)
			(layers "*.Cu" "*.Mask")
			(remove_unused_layers no)
			(clearance 0.127)
			(thermal_gap 0.127)
		)
		(pad "" thru_hole circle
			(at 2.29997 132.299964 90)
			(size 2.8194 2.8194)
			(drill 2.4384)
			(layers "*.Cu" "*.Mask")
			(remove_unused_layers no)
			(clearance 0.127)
			(thermal_gap 0.127)
		)
		(pad "1" smd rect
			(at 0 0 90)
			(size 1.8034 0.508)
			(layers "F.Cu" "F.Mask" "F.Paste")
			(net "P12V_NVDIMM_GHJ")
		)
		(pad "2" smd rect
			(at 0 0.849884 90)
			(size 1.8034 0.508)
			(layers "F.Cu" "F.Mask" "F.Paste")
			(net "GND")
		)
		(pad "3" smd rect
			(at 0 1.700022 90)
			(size 1.8034 0.508)
			(layers "F.Cu" "F.Mask" "F.Paste")
			(net "M_H_DQ<5>")
		)
		(pad "4" smd rect
			(at 0 2.549906 90)
			(size 1.8034 0.508)
			(layers "F.Cu" "F.Mask" "F.Paste")
			(net "GND")
		)
		(pad "5" smd rect
			(at 0 3.400044 90)
			(size 1.8034 0.508)
			(layers "F.Cu" "F.Mask" "F.Paste")
			(net "M_H_DQ<1>")
		)
		(pad "6" smd rect
			(at 0 4.249928 90)
			(size 1.8034 0.508)
			(layers "F.Cu" "F.Mask" "F.Paste")
			(net "GND")
		)
		(pad "7" smd rect
			(at 0 5.100066 90)
			(size 1.8034 0.508)
			(layers "F.Cu" "F.Mask" "F.Paste")
			(net "M_H_DQS_DP<9>")
		)
		(pad "8" smd rect
			(at 0 5.94995 90)
			(size 1.8034 0.508)
			(layers "F.Cu" "F.Mask" "F.Paste")
			(net "M_H_DQS_DN<9>")
		)
		(pad "9" smd rect
			(at 0 6.800088 90)
			(size 1.8034 0.508)
			(layers "F.Cu" "F.Mask" "F.Paste")
			(net "GND")
		)
		(pad "10" smd rect
			(at 0 7.649972 90)
			(size 1.8034 0.508)
			(layers "F.Cu" "F.Mask" "F.Paste")
			(net "M_H_DQ<7>")
		)
		(pad "11" smd rect
			(at 0 8.50011 90)
			(size 1.8034 0.508)
			(layers "F.Cu" "F.Mask" "F.Paste")
			(net "GND")
		)
		(pad "12" smd rect
			(at 0 9.349994 90)
			(size 1.8034 0.508)
			(layers "F.Cu" "F.Mask" "F.Paste")
			(net "M_H_DQ<3>")
		)
		(pad "13" smd rect
			(at 0 10.199878 90)
			(size 1.8034 0.508)
			(layers "F.Cu" "F.Mask" "F.Paste")
			(net "GND")
		)
		(pad "14" smd rect
			(at 0 11.050016 90)
			(size 1.8034 0.508)
			(layers "F.Cu" "F.Mask" "F.Paste")
			(net "M_H_DQ<13>")
		)
		(pad "15" smd rect
			(at 0 11.8999 90)
			(size 1.8034 0.508)
			(layers "F.Cu" "F.Mask" "F.Paste")
			(net "GND")
		)
		(pad "16" smd rect
			(at 0 12.750038 90)
			(size 1.8034 0.508)
			(layers "F.Cu" "F.Mask" "F.Paste")
			(net "M_H_DQ<9>")
		)
		(pad "17" smd rect
			(at 0 13.599922 90)
			(size 1.8034 0.508)
			(layers "F.Cu" "F.Mask" "F.Paste")
			(net "GND")
		)
		(pad "18" smd rect
			(at 0 14.45006 90)
			(size 1.8034 0.508)
			(layers "F.Cu" "F.Mask" "F.Paste")
			(net "M_H_DQS_DP<10>")
		)
		(pad "19" smd rect
			(at 0 15.299944 90)
			(size 1.8034 0.508)
			(layers "F.Cu" "F.Mask" "F.Paste")
			(net "M_H_DQS_DN<10>")
		)
		(pad "20" smd rect
			(at 0 16.150082 90)
			(size 1.8034 0.508)
			(layers "F.Cu" "F.Mask" "F.Paste")
			(net "GND")
		)
		(pad "21" smd rect
			(at 0 16.999966 90)
			(size 1.8034 0.508)
			(layers "F.Cu" "F.Mask" "F.Paste")
			(net "M_H_DQ<15>")
		)
		(pad "22" smd rect
			(at 0 17.850104 90)
			(size 1.8034 0.508)
			(layers "F.Cu" "F.Mask" "F.Paste")
			(net "GND")
		)
		(pad "23" smd rect
			(at 0 18.699988 90)
			(size 1.8034 0.508)
			(layers "F.Cu" "F.Mask" "F.Paste")
			(net "M_H_DQ<11>")
		)
		(pad "24" smd rect
			(at 0 19.550126 90)
			(size 1.8034 0.508)
			(layers "F.Cu" "F.Mask" "F.Paste")
			(net "GND")
		)
		(pad "25" smd rect
			(at 0 20.40001 90)
			(size 1.8034 0.508)
			(layers "F.Cu" "F.Mask" "F.Paste")
			(net "M_H_DQ<21>")
		)
		(pad "26" smd rect
			(at 0 21.249894 90)
			(size 1.8034 0.508)
			(layers "F.Cu" "F.Mask" "F.Paste")
			(net "GND")
		)
		(pad "27" smd rect
			(at 0 22.100032 90)
			(size 1.8034 0.508)
			(layers "F.Cu" "F.Mask" "F.Paste")
			(net "M_H_DQ<17>")
		)
		(pad "28" smd rect
			(at 0 22.949916 90)
			(size 1.8034 0.508)
			(layers "F.Cu" "F.Mask" "F.Paste")
			(net "GND")
		)
		(pad "29" smd rect
			(at 0 23.800054 90)
			(size 1.8034 0.508)
			(layers "F.Cu" "F.Mask" "F.Paste")
			(net "M_H_DQS_DP<11>")
		)
		(pad "30" smd rect
			(at 0 24.649938 90)
			(size 1.8034 0.508)
			(layers "F.Cu" "F.Mask" "F.Paste")
			(net "M_H_DQS_DN<11>")
		)
		(pad "31" smd rect
			(at 0 25.500076 90)
			(size 1.8034 0.508)
			(layers "F.Cu" "F.Mask" "F.Paste")
			(net "GND")
		)
		(pad "32" smd rect
			(at 0 26.34996 90)
			(size 1.8034 0.508)
			(layers "F.Cu" "F.Mask" "F.Paste")
			(net "M_H_DQ<23>")
		)
		(pad "33" smd rect
			(at 0 27.200098 90)
			(size 1.8034 0.508)
			(layers "F.Cu" "F.Mask" "F.Paste")
			(net "GND")
		)
		(pad "34" smd rect
			(at 0 28.049982 90)
			(size 1.8034 0.508)
			(layers "F.Cu" "F.Mask" "F.Paste")
			(net "M_H_DQ<19>")
		)
		(pad "35" smd rect
			(at 0 28.90012 90)
			(size 1.8034 0.508)
			(layers "F.Cu" "F.Mask" "F.Paste")
			(net "GND")
		)
		(pad "36" smd rect
			(at 0 29.750004 90)
			(size 1.8034 0.508)
			(layers "F.Cu" "F.Mask" "F.Paste")
			(net "M_H_DQ<29>")
		)
		(pad "37" smd rect
			(at 0 30.599888 90)
			(size 1.8034 0.508)
			(layers "F.Cu" "F.Mask" "F.Paste")
			(net "GND")
		)
		(pad "38" smd rect
			(at 0 31.450026 90)
			(size 1.8034 0.508)
			(layers "F.Cu" "F.Mask" "F.Paste")
			(net "M_H_DQ<25>")
		)
		(pad "39" smd rect
			(at 0 32.29991 90)
			(size 1.8034 0.508)
			(layers "F.Cu" "F.Mask" "F.Paste")
			(net "GND")
		)
		(pad "40" smd rect
			(at 0 33.150048 90)
			(size 1.8034 0.508)
			(layers "F.Cu" "F.Mask" "F.Paste")
			(net "M_H_DQS_DP<12>")
		)
		(pad "41" smd rect
			(at 0 33.999932 90)
			(size 1.8034 0.508)
			(layers "F.Cu" "F.Mask" "F.Paste")
			(net "M_H_DQS_DN<12>")
		)
		(pad "42" smd rect
			(at 0 34.85007 90)
			(size 1.8034 0.508)
			(layers "F.Cu" "F.Mask" "F.Paste")
			(net "GND")
		)
		(pad "43" smd rect
			(at 0 35.699954 90)
			(size 1.8034 0.508)
			(layers "F.Cu" "F.Mask" "F.Paste")
			(net "M_H_DQ<31>")
		)
		(pad "44" smd rect
			(at 0 36.550092 90)
			(size 1.8034 0.508)
			(layers "F.Cu" "F.Mask" "F.Paste")
			(net "GND")
		)
		(pad "45" smd rect
			(at 0 37.399976 90)
			(size 1.8034 0.508)
			(layers "F.Cu" "F.Mask" "F.Paste")
			(net "M_H_DQ<27>")
		)
		(pad "46" smd rect
			(at 0 38.250114 90)
			(size 1.8034 0.508)
			(layers "F.Cu" "F.Mask" "F.Paste")
			(net "GND")
		)
		(pad "47" smd rect
			(at 0 39.099998 90)
			(size 1.8034 0.508)
			(layers "F.Cu" "F.Mask" "F.Paste")
			(net "M_H_ECC<5>")
		)
	)
)
